;LEADER: 12 
;HEADER: 
;CODE  : ASCII 
;FILE  : 9127_F0T_Expander_BD_F_v02_0110_1240-bd-18-17.drl for backdrilling ... from layer BOTTOM to layer GND7
;DESIGN: 9127_F0T_Expander_BD_F_v02_0110_1240.brd
;MUST-NOT-CUT-LAYER = IN6,  MAX_DRILL_DEPTH = 9.95 MILS,  MFG_STUB_LENGTH = 0.00 MILS
;   BackdrillSize 1. = 15.700000 Tolerance = +0.000000/-0.000000 NON_PLATED MILS Quantity = 128
;   BackdrillSize 2. = 17.700000 Tolerance = +0.000000/-0.000000 NON_PLATED MILS Quantity = 12
;   BackdrillSize 3. = 19.900000 Tolerance = +0.000000/-0.000000 NON_PLATED MILS Quantity = 132
%
G90
X0324606Y1247243
X0302165Y1250984
X0302165Y1254724
X0313385Y1243503
X0290944Y1243503
X0305905Y1247243
X0290944Y1247243
X0305905Y1243503
X0298425Y1243503
X0309645Y1250984
X0317125Y1250984
X0320866Y1247243
X0313385Y1247243
X0298425Y1247243
X0294685Y1250984
X0309645Y1254724
X0317125Y1254724
X0294685Y1254724
X0313385Y1217322
X0324606Y1206102
X0324606Y1221062
X0320866Y1213582
X0320866Y1206102
X0317125Y1202362
X0324606Y1198621
X0313385Y1202362
X0320866Y1198621
X0313385Y1209842
X0320866Y1221062
X0324606Y1213582
X0317125Y1209842
X0317125Y1217322
X0643307Y1243503
X0643307Y1247243
X0647047Y1250984
X0647047Y1254724
X0650787Y1243503
X0650787Y1247243
X0654527Y1250984
X0654527Y1254724
X0639567Y1254724
X0628346Y1247243
X0628346Y1243503
X0635827Y1247243
X0632086Y1250984
X0635827Y1243503
X0639567Y1250984
X0632086Y1254724
X0736811Y1250984
X0736811Y1254724
X0744291Y1250984
X0725590Y1247243
X0733071Y1243503
X0729331Y1254724
X0725590Y1243503
X0740551Y1247243
X0740551Y1243503
X0721850Y1254724
X0718110Y1247243
X0721850Y1250984
X0718110Y1243503
X0744291Y1254724
X0733071Y1247243
X0729331Y1250984
X1227558Y1217322
X1235039Y1206102
X1227558Y1202362
X1231298Y1217322
X1235039Y1198621
X1235039Y1221062
X1238779Y1213582
X1238779Y1198621
X1231298Y1202362
X1227558Y1209842
X1238779Y1206102
X1231298Y1209842
X1238779Y1221062
X1235039Y1213582
X1216338Y1250984
X1235039Y1247243
X1231298Y1250984
X1216338Y1254724
X1227558Y1243503
X1208858Y1250984
X1223818Y1250984
X1205117Y1247243
X1208858Y1254724
X1212598Y1247243
X1205117Y1243503
X1238779Y1247243
X1223818Y1254724
X1231298Y1254724
X1220078Y1243503
X1220078Y1247243
X1212598Y1243503
X1227558Y1247243
X1542519Y1247243
X1553740Y1254724
X1568700Y1250984
X1546259Y1254724
X1542519Y1243503
X1553740Y1250984
X1557480Y1243503
X1550000Y1247243
X1557480Y1247243
X1564960Y1247243
X1564960Y1243503
X1546259Y1250984
X1550000Y1243503
X1561220Y1254724
X1561220Y1250984
X1568700Y1254724
X1658464Y1250984
X1643504Y1254724
X1658464Y1254724
X1639763Y1247243
X1650984Y1254724
X1647244Y1243503
X1654724Y1247243
X1647244Y1247243
X1650984Y1250984
X1643504Y1250984
X1632283Y1247243
X1636023Y1250984
X1639763Y1243503
X1654724Y1243503
X1636023Y1254724
X1632283Y1243503
M00
X0213969Y1450853
X0213969Y1447453
X0213969Y1458453
X0213969Y1461853
X0924564Y0344041
X0940997Y0335312
X0927964Y0344041
X0940997Y0331912
X0917882Y0324816
X0919354Y0344150
X0917882Y0328216
X0915954Y0344150
M00
X0118543Y1601142
X0109882Y1596811
X0118543Y1596024
X0109882Y1591693
X0135866Y1601142
X0127205Y1596811
X0135866Y1596024
X0127205Y1591693
X0153189Y1601142
X0144528Y1596811
X0153189Y1596024
X0144528Y1591693
X0161850Y1596811
X0161850Y1591693
X0118543Y1498780
X0109882Y1494449
X0118543Y1493662
X0109882Y1489331
X0135866Y1498780
X0127205Y1494449
X0135866Y1493662
X0127205Y1489331
X0153189Y1498780
X0144528Y1494449
X0153189Y1493662
X0144528Y1489331
X0161850Y1494449
X0161850Y1489331
X0170512Y1498780
X0170512Y1493662
X0187835Y1468071
X0187835Y1462953
X0179173Y1463741
X0179173Y1458622
X0170512Y1601142
X0170512Y1596024
X0465000Y1468071
X0456339Y1463741
X0465000Y1462953
X0456339Y1458622
X0465000Y1585788
X0456339Y1581457
X0465000Y1580670
X0456339Y1576339
X0482323Y1585788
X0473662Y1581457
X0482323Y1580670
X0473662Y1576339
X0499646Y1585788
X0490985Y1581457
X0499646Y1580670
X0490985Y1576339
X0516969Y1585788
X0508307Y1581457
X0516969Y1580670
X0508307Y1576339
X0482323Y1468071
X0473662Y1463741
X0482323Y1462953
X0473662Y1458622
X0499646Y1468071
X0490985Y1463741
X0499646Y1462953
X0490985Y1458622
X0516969Y1468071
X0508307Y1463741
X0516969Y1462953
X0508307Y1458622
X1140511Y1601142
X1131850Y1596811
X1140511Y1596024
X1131850Y1591693
X1157834Y1601142
X1149173Y1596811
X1157834Y1596024
X1149173Y1591693
X1166496Y1596811
X1166496Y1591693
X1140511Y1498780
X1131850Y1494449
X1140511Y1493662
X1131850Y1489331
X1157834Y1498780
X1149173Y1494449
X1157834Y1493662
X1149173Y1489331
X1166496Y1494449
X1166496Y1489331
X1175157Y1498780
X1175157Y1493662
X1192480Y1498780
X1183818Y1494449
X1192480Y1493662
X1183818Y1489331
X1175157Y1601142
X1175157Y1596024
X1192480Y1601142
X1183818Y1596811
X1192480Y1596024
X1183818Y1591693
X1486968Y1585788
X1478307Y1581457
X1486968Y1580670
X1478307Y1576339
X1504291Y1585788
X1495630Y1581457
X1504291Y1580670
X1495630Y1576339
X1521614Y1585788
X1512953Y1581457
X1521614Y1580670
X1512953Y1576339
X1538937Y1585788
X1530275Y1581457
X1538937Y1580670
X1530275Y1576339
X1486968Y1468071
X1478307Y1463741
X1486968Y1462953
X1478307Y1458622
X1504291Y1468071
X1495630Y1463741
X1504291Y1462953
X1495630Y1458622
X1521614Y1468071
X1512953Y1463741
X1521614Y1462953
X1512953Y1458622
X1538937Y1468071
X1530275Y1463741
X1538937Y1462953
X1530275Y1458622
M30
